(kicad_pcb
	(version 20260206)
	(generator "pcbnew")
	(generator_version "10.0")
	(general
		(thickness 1.6)
		(legacy_teardrops no)
	)
	(paper "A4")
	(title_block
		(title "01162023_DA0F0TEBIF0_F0T_Expander_BD_F_brd_V02_OCP.brd")
		(comment 1 "Grand Teton / footprints 9524-9532 of 9728")
	)
	(layers
		(0 "F.Cu" signal "TOP")
		(4 "In1.Cu" signal "GND")
		(6 "In2.Cu" signal "VCC")
		(8 "In3.Cu" signal "VCC1")
		(10 "In4.Cu" signal "GND1")
		(12 "In5.Cu" signal "IN1")
		(14 "In6.Cu" signal "GND2")
		(16 "In7.Cu" signal "IN2")
		(18 "In8.Cu" signal "GND3")
		(20 "In9.Cu" signal "IN3")
		(22 "In10.Cu" signal "GND4")
		(24 "In11.Cu" signal "IN4")
		(26 "In12.Cu" signal "GND5")
		(28 "In13.Cu" signal "IN5")
		(30 "In14.Cu" signal "GND6")
		(32 "In15.Cu" signal "IN6")
		(34 "In16.Cu" signal "GND7")
		(2 "B.Cu" signal "BOTTOM")
		(9 "F.Adhes" user "F.Adhesive")
		(11 "B.Adhes" user "B.Adhesive")
		(13 "F.Paste" user "Package Geometry/Pastemask Top")
		(15 "B.Paste" user "Package Geometry/Pastemask Bottom")
		(5 "F.SilkS" user "Ref Des/Silkscreen Top")
		(7 "B.SilkS" user "Ref Des/Silkscreen Bottom")
		(1 "F.Mask" user "Board Geometry/Soldermask Top")
		(3 "B.Mask" user "Board Geometry/Soldermask Bottom")
		(17 "Dwgs.User" user "User.Drawings")
		(19 "Cmts.User" user "User.Comments")
		(21 "Eco1.User" user "User.Eco1")
		(23 "Eco2.User" user "User.Eco2")
		(25 "Edge.Cuts" user "Board Geometry/Outline")
		(27 "Margin" user)
		(31 "F.CrtYd" user "Package Geometry/Place Bound Top")
		(29 "B.CrtYd" user "Package Geometry/Place Bound Bottom")
		(35 "F.Fab" user "Ref Des/Assembly Top")
		(33 "B.Fab" user "Ref Des/Assembly Bottom")
	)
	(footprint ""
		(layer "B.Cu")
		(at 397.97482 -293.99992 -90)
		(property "Reference" "C1879"
			(at 0 0 90)
			(layer "B.SilkS")
			(hide yes)
			(effects
				(font
					(size 1.27 1.27)
				)
				(justify mirror)
			)
		)
		(property "Value" ""
			(at 0 0 90)
			(layer "B.Fab")
			(effects
				(font
					(size 1.27 1.27)
				)
				(justify mirror)
			)
		)
		(duplicate_pad_numbers_are_jumpers no)
		(fp_line
			(start -0.299974 0.150114)
			(end 0.299974 0.150114)
			(stroke
				(width 0.1)
				(type default)
			)
			(layer "B.Fab")
		)
		(fp_line
			(start 0.299974 0.150114)
			(end 0.299974 -0.150114)
			(stroke
				(width 0.1)
				(type default)
			)
			(layer "B.Fab")
		)
		(fp_line
			(start -0.299974 -0.150114)
			(end -0.299974 0.150114)
			(stroke
				(width 0.1)
				(type default)
			)
			(layer "B.Fab")
		)
		(fp_line
			(start 0.299974 -0.150114)
			(end -0.299974 -0.150114)
			(stroke
				(width 0.1)
				(type default)
			)
			(layer "B.Fab")
		)
		(pad "1" smd rect
			(at 0.2667 0 90)
			(size 0.3048 0.381)
			(layers "B.Cu" "B.Mask" "B.Paste")
			(net "P0V8_PEX3")
		)
		(pad "2" smd rect
			(at -0.2667 0 90)
			(size 0.3048 0.381)
			(layers "B.Cu" "B.Mask" "B.Paste")
			(net "GND")
		)
	)
	(footprint ""
		(layer "B.Cu")
		(at 334.227932 -275.813774)
		(property "Reference" "PC6618"
			(at 0 0 0)
			(layer "B.SilkS")
			(hide yes)
			(effects
				(font
					(size 1.27 1.27)
				)
				(justify mirror)
			)
		)
		(property "Value" ""
			(at 0 0 0)
			(layer "B.Fab")
			(effects
				(font
					(size 1.27 1.27)
				)
				(justify mirror)
			)
		)
		(duplicate_pad_numbers_are_jumpers no)
		(fp_line
			(start -1.524 -0.762)
			(end -1.524 0.762)
			(stroke
				(width 0.1524)
				(type default)
			)
			(layer "B.SilkS")
		)
		(fp_line
			(start -1.524 0.762)
			(end 1.524 0.762)
			(stroke
				(width 0.1524)
				(type default)
			)
			(layer "B.SilkS")
		)
		(fp_line
			(start 1.524 -0.762)
			(end -1.524 -0.762)
			(stroke
				(width 0.1524)
				(type default)
			)
			(layer "B.SilkS")
		)
		(fp_line
			(start 1.524 0.762)
			(end 1.524 -0.762)
			(stroke
				(width 0.1524)
				(type default)
			)
			(layer "B.SilkS")
		)
		(fp_line
			(start -1.1049 -0.724916)
			(end 1.1049 -0.724916)
			(stroke
				(width 0.1)
				(type default)
			)
			(layer "B.Fab")
		)
		(fp_line
			(start -1.1049 0.724916)
			(end -1.1049 -0.724916)
			(stroke
				(width 0.1)
				(type default)
			)
			(layer "B.Fab")
		)
		(fp_line
			(start 1.1049 -0.724916)
			(end 1.1049 0.724916)
			(stroke
				(width 0.1)
				(type default)
			)
			(layer "B.Fab")
		)
		(fp_line
			(start 1.1049 0.724916)
			(end -1.1049 0.724916)
			(stroke
				(width 0.1)
				(type default)
			)
			(layer "B.Fab")
		)
		(pad "1" smd rect
			(at 0.889 0)
			(size 1.016 1.27)
			(layers "B.Cu" "B.Mask" "B.Paste")
			(net "SW_P12V_P0V8_PEX2_FLT")
		)
		(pad "2" smd rect
			(at -0.889 0)
			(size 1.016 1.27)
			(layers "B.Cu" "B.Mask" "B.Paste")
			(net "GND")
		)
	)
	(footprint ""
		(layer "B.Cu")
		(at 57.749948 -301.599854 -90)
		(property "Reference" "C1231"
			(at 0 0 90)
			(layer "B.SilkS")
			(hide yes)
			(effects
				(font
					(size 1.27 1.27)
				)
				(justify mirror)
			)
		)
		(property "Value" ""
			(at 0 0 90)
			(layer "B.Fab")
			(effects
				(font
					(size 1.27 1.27)
				)
				(justify mirror)
			)
		)
		(duplicate_pad_numbers_are_jumpers no)
		(fp_line
			(start -0.299974 0.150114)
			(end 0.299974 0.150114)
			(stroke
				(width 0.1)
				(type default)
			)
			(layer "B.Fab")
		)
		(fp_line
			(start 0.299974 0.150114)
			(end 0.299974 -0.150114)
			(stroke
				(width 0.1)
				(type default)
			)
			(layer "B.Fab")
		)
		(fp_line
			(start -0.299974 -0.150114)
			(end -0.299974 0.150114)
			(stroke
				(width 0.1)
				(type default)
			)
			(layer "B.Fab")
		)
		(fp_line
			(start 0.299974 -0.150114)
			(end -0.299974 -0.150114)
			(stroke
				(width 0.1)
				(type default)
			)
			(layer "B.Fab")
		)
		(pad "1" smd rect
			(at 0.2667 0 90)
			(size 0.3048 0.381)
			(layers "B.Cu" "B.Mask" "B.Paste")
			(net "P0V8_SERDES_VDDA_PEX0")
		)
		(pad "2" smd rect
			(at -0.2667 0 90)
			(size 0.3048 0.381)
			(layers "B.Cu" "B.Mask" "B.Paste")
			(net "GND")
		)
	)
	(footprint ""
		(layer "B.Cu")
		(at 122.653552 -308.580028 90)
		(property "Reference" "C1415"
			(at 0 0 90)
			(layer "B.SilkS")
			(hide yes)
			(effects
				(font
					(size 1.27 1.27)
				)
				(justify mirror)
			)
		)
		(property "Value" ""
			(at 0 0 90)
			(layer "B.Fab")
			(effects
				(font
					(size 1.27 1.27)
				)
				(justify mirror)
			)
		)
		(duplicate_pad_numbers_are_jumpers no)
		(fp_line
			(start 1.2954 -0.5842)
			(end -1.2954 -0.5842)
			(stroke
				(width 0.1524)
				(type default)
			)
			(layer "B.SilkS")
		)
		(fp_line
			(start -1.2954 -0.5842)
			(end -1.2954 0.5842)
			(stroke
				(width 0.1524)
				(type default)
			)
			(layer "B.SilkS")
		)
		(fp_line
			(start 1.2954 0.5842)
			(end 1.2954 -0.5842)
			(stroke
				(width 0.1524)
				(type default)
			)
			(layer "B.SilkS")
		)
		(fp_line
			(start -1.2954 0.5842)
			(end 1.2954 0.5842)
			(stroke
				(width 0.1524)
				(type default)
			)
			(layer "B.SilkS")
		)
		(fp_line
			(start 0.8636 -0.4572)
			(end -0.8636 -0.4572)
			(stroke
				(width 0.1)
				(type default)
			)
			(layer "B.Fab")
		)
		(fp_line
			(start -0.8636 -0.4572)
			(end -0.8636 -0.4064)
			(stroke
				(width 0.1)
				(type default)
			)
			(layer "B.Fab")
		)
		(fp_line
			(start 1.1938 -0.4064)
			(end 0.8636 -0.4064)
			(stroke
				(width 0.1)
				(type default)
			)
			(layer "B.Fab")
		)
		(fp_line
			(start 0.8636 -0.4064)
			(end 0.8636 -0.4572)
			(stroke
				(width 0.1)
				(type default)
			)
			(layer "B.Fab")
		)
		(fp_line
			(start -0.8636 -0.4064)
			(end -1.1938 -0.4064)
			(stroke
				(width 0.1)
				(type default)
			)
			(layer "B.Fab")
		)
		(fp_line
			(start -1.1938 -0.4064)
			(end -1.1938 0.4064)
			(stroke
				(width 0.1)
				(type default)
			)
			(layer "B.Fab")
		)
		(fp_line
			(start 1.1938 0.4064)
			(end 1.1938 -0.4064)
			(stroke
				(width 0.1)
				(type default)
			)
			(layer "B.Fab")
		)
		(fp_line
			(start 0.8636 0.4064)
			(end 1.1938 0.4064)
			(stroke
				(width 0.1)
				(type default)
			)
			(layer "B.Fab")
		)
		(fp_line
			(start -0.8636 0.4064)
			(end -0.8636 0.4572)
			(stroke
				(width 0.1)
				(type default)
			)
			(layer "B.Fab")
		)
		(fp_line
			(start -1.1938 0.4064)
			(end -0.8636 0.4064)
			(stroke
				(width 0.1)
				(type default)
			)
			(layer "B.Fab")
		)
		(fp_line
			(start 0.8636 0.4572)
			(end 0.8636 0.4064)
			(stroke
				(width 0.1)
				(type default)
			)
			(layer "B.Fab")
		)
		(fp_line
			(start -0.8636 0.4572)
			(end 0.8636 0.4572)
			(stroke
				(width 0.1)
				(type default)
			)
			(layer "B.Fab")
		)
		(pad "1" smd rect
			(at 0.7366 0)
			(size 0.7112 0.8128)
			(layers "B.Cu" "B.Mask" "B.Paste")
			(net "P0V8_SERDES_VDDA_PEX1")
		)
		(pad "2" smd rect
			(at -0.7366 0)
			(size 0.7112 0.8128)
			(layers "B.Cu" "B.Mask" "B.Paste")
			(net "GND")
		)
	)
	(footprint ""
		(layer "B.Cu")
		(at 77.541882 -101.069648 180)
		(property "Reference" "R76"
			(at 0 0 0)
			(layer "B.SilkS")
			(hide yes)
			(effects
				(font
					(size 1.27 1.27)
				)
				(justify mirror)
			)
		)
		(property "Value" ""
			(at 0 0 0)
			(layer "B.Fab")
			(effects
				(font
					(size 1.27 1.27)
				)
				(justify mirror)
			)
		)
		(duplicate_pad_numbers_are_jumpers no)
		(fp_line
			(start 0.7874 0.4064)
			(end 0.7874 -0.4064)
			(stroke
				(width 0.1524)
				(type default)
			)
			(layer "B.SilkS")
		)
		(fp_line
			(start 0.7874 -0.4064)
			(end -0.7874 -0.4064)
			(stroke
				(width 0.1524)
				(type default)
			)
			(layer "B.SilkS")
		)
		(fp_line
			(start -0.7874 0.4064)
			(end 0.7874 0.4064)
			(stroke
				(width 0.1524)
				(type default)
			)
			(layer "B.SilkS")
		)
		(fp_line
			(start -0.7874 -0.4064)
			(end -0.7874 0.4064)
			(stroke
				(width 0.1524)
				(type default)
			)
			(layer "B.SilkS")
		)
		(fp_line
			(start 0.67945 0.3048)
			(end 0.67945 -0.305054)
			(stroke
				(width 0.1)
				(type default)
			)
			(layer "B.Fab")
		)
		(fp_line
			(start 0.67945 -0.305054)
			(end 0.12065 -0.305054)
			(stroke
				(width 0.1)
				(type default)
			)
			(layer "B.Fab")
		)
		(fp_line
			(start 0.12065 0.3048)
			(end 0.67945 0.3048)
			(stroke
				(width 0.1)
				(type default)
			)
			(layer "B.Fab")
		)
		(fp_line
			(start 0.12065 0.2794)
			(end 0.12065 0.3048)
			(stroke
				(width 0.1)
				(type default)
			)
			(layer "B.Fab")
		)
		(fp_line
			(start 0.12065 -0.2794)
			(end -0.12065 -0.2794)
			(stroke
				(width 0.1)
				(type default)
			)
			(layer "B.Fab")
		)
		(fp_line
			(start 0.12065 -0.305054)
			(end 0.12065 -0.2794)
			(stroke
				(width 0.1)
				(type default)
			)
			(layer "B.Fab")
		)
		(fp_line
			(start -0.120396 0.3048)
			(end -0.120396 0.2794)
			(stroke
				(width 0.1)
				(type default)
			)
			(layer "B.Fab")
		)
		(fp_line
			(start -0.120396 0.2794)
			(end 0.12065 0.2794)
			(stroke
				(width 0.1)
				(type default)
			)
			(layer "B.Fab")
		)
		(fp_line
			(start -0.12065 -0.2794)
			(end -0.12065 -0.3048)
			(stroke
				(width 0.1)
				(type default)
			)
			(layer "B.Fab")
		)
		(fp_line
			(start -0.12065 -0.3048)
			(end -0.67945 -0.3048)
			(stroke
				(width 0.1)
				(type default)
			)
			(layer "B.Fab")
		)
		(fp_line
			(start -0.67945 0.3048)
			(end -0.120396 0.3048)
			(stroke
				(width 0.1)
				(type default)
			)
			(layer "B.Fab")
		)
		(fp_line
			(start -0.67945 -0.3048)
			(end -0.67945 0.3048)
			(stroke
				(width 0.1)
				(type default)
			)
			(layer "B.Fab")
		)
		(pad "1" smd circle
			(at 0.40005 0)
			(size 0 0)
			(layers "B.Cu" "B.Mask" "B.Paste")
			(net "NIC1_SLOT_ID0")
		)
		(pad "2" smd circle
			(at -0.40005 0)
			(size 0 0)
			(layers "B.Cu" "B.Mask" "B.Paste")
			(net "P3V3_NIC1")
		)
	)
	(footprint ""
		(layer "B.Cu")
		(at 418.399976 -288.774886 180)
		(property "Reference" "C3526"
			(at 0 0 0)
			(layer "B.SilkS")
			(hide yes)
			(effects
				(font
					(size 1.27 1.27)
				)
				(justify mirror)
			)
		)
		(property "Value" ""
			(at 0 0 0)
			(layer "B.Fab")
			(effects
				(font
					(size 1.27 1.27)
				)
				(justify mirror)
			)
		)
		(duplicate_pad_numbers_are_jumpers no)
		(fp_line
			(start 0.299974 0.150114)
			(end 0.299974 -0.150114)
			(stroke
				(width 0.1)
				(type default)
			)
			(layer "B.Fab")
		)
		(fp_line
			(start 0.299974 -0.150114)
			(end -0.299974 -0.150114)
			(stroke
				(width 0.1)
				(type default)
			)
			(layer "B.Fab")
		)
		(fp_line
			(start -0.299974 0.150114)
			(end 0.299974 0.150114)
			(stroke
				(width 0.1)
				(type default)
			)
			(layer "B.Fab")
		)
		(fp_line
			(start -0.299974 -0.150114)
			(end -0.299974 0.150114)
			(stroke
				(width 0.1)
				(type default)
			)
			(layer "B.Fab")
		)
		(pad "1" smd rect
			(at 0.2667 0)
			(size 0.3048 0.381)
			(layers "B.Cu" "B.Mask" "B.Paste")
			(net "P1V8_PEX")
		)
		(pad "2" smd rect
			(at -0.2667 0)
			(size 0.3048 0.381)
			(layers "B.Cu" "B.Mask" "B.Paste")
			(net "GND")
		)
	)
	(footprint ""
		(layer "B.Cu")
		(at 104.359964 -326.990202 90)
		(property "Reference" "C2699"
			(at 0 0 90)
			(layer "B.SilkS")
			(hide yes)
			(effects
				(font
					(size 1.27 1.27)
				)
				(justify mirror)
			)
		)
		(property "Value" ""
			(at 0 0 90)
			(layer "B.Fab")
			(effects
				(font
					(size 1.27 1.27)
				)
				(justify mirror)
			)
		)
		(duplicate_pad_numbers_are_jumpers no)
		(fp_line
			(start 0.7874 -0.4064)
			(end -0.7874 -0.4064)
			(stroke
				(width 0.1524)
				(type default)
			)
			(layer "B.SilkS")
		)
		(fp_line
			(start -0.7874 -0.4064)
			(end -0.7874 0.4064)
			(stroke
				(width 0.1524)
				(type default)
			)
			(layer "B.SilkS")
		)
		(fp_line
			(start 0.7874 0.4064)
			(end 0.7874 -0.4064)
			(stroke
				(width 0.1524)
				(type default)
			)
			(layer "B.SilkS")
		)
		(fp_line
			(start -0.7874 0.4064)
			(end 0.7874 0.4064)
			(stroke
				(width 0.1524)
				(type default)
			)
			(layer "B.SilkS")
		)
		(fp_line
			(start 0.67945 -0.305054)
			(end 0.12065 -0.305054)
			(stroke
				(width 0.1)
				(type default)
			)
			(layer "B.Fab")
		)
		(fp_line
			(start 0.12065 -0.305054)
			(end 0.12065 -0.2794)
			(stroke
				(width 0.1)
				(type default)
			)
			(layer "B.Fab")
		)
		(fp_line
			(start -0.12065 -0.3048)
			(end -0.67945 -0.3048)
			(stroke
				(width 0.1)
				(type default)
			)
			(layer "B.Fab")
		)
		(fp_line
			(start -0.67945 -0.3048)
			(end -0.67945 0.3048)
			(stroke
				(width 0.1)
				(type default)
			)
			(layer "B.Fab")
		)
		(fp_line
			(start 0.12065 -0.2794)
			(end -0.12065 -0.2794)
			(stroke
				(width 0.1)
				(type default)
			)
			(layer "B.Fab")
		)
		(fp_line
			(start -0.12065 -0.2794)
			(end -0.12065 -0.3048)
			(stroke
				(width 0.1)
				(type default)
			)
			(layer "B.Fab")
		)
		(fp_line
			(start 0.12065 0.2794)
			(end 0.12065 0.3048)
			(stroke
				(width 0.1)
				(type default)
			)
			(layer "B.Fab")
		)
		(fp_line
			(start -0.120396 0.2794)
			(end 0.12065 0.2794)
			(stroke
				(width 0.1)
				(type default)
			)
			(layer "B.Fab")
		)
		(fp_line
			(start 0.67945 0.3048)
			(end 0.67945 -0.305054)
			(stroke
				(width 0.1)
				(type default)
			)
			(layer "B.Fab")
		)
		(fp_line
			(start 0.12065 0.3048)
			(end 0.67945 0.3048)
			(stroke
				(width 0.1)
				(type default)
			)
			(layer "B.Fab")
		)
		(fp_line
			(start -0.120396 0.3048)
			(end -0.120396 0.2794)
			(stroke
				(width 0.1)
				(type default)
			)
			(layer "B.Fab")
		)
		(fp_line
			(start -0.67945 0.3048)
			(end -0.120396 0.3048)
			(stroke
				(width 0.1)
				(type default)
			)
			(layer "B.Fab")
		)
		(pad "1" smd circle
			(at 0.40005 0 270)
			(size 0 0)
			(layers "B.Cu" "B.Mask" "B.Paste")
			(net "P3V3_CLK_BUFFER_9ZXL0451E_VZX3P3")
		)
		(pad "2" smd circle
			(at -0.40005 0 270)
			(size 0 0)
			(layers "B.Cu" "B.Mask" "B.Paste")
			(net "GND")
		)
	)
	(footprint ""
		(layer "B.Cu")
		(at 69.149976 -297.32478 180)
		(property "Reference" "C1161"
			(at 0 0 0)
			(layer "B.SilkS")
			(hide yes)
			(effects
				(font
					(size 1.27 1.27)
				)
				(justify mirror)
			)
		)
		(property "Value" ""
			(at 0 0 0)
			(layer "B.Fab")
			(effects
				(font
					(size 1.27 1.27)
				)
				(justify mirror)
			)
		)
		(duplicate_pad_numbers_are_jumpers no)
		(fp_line
			(start 0.299974 0.150114)
			(end 0.299974 -0.150114)
			(stroke
				(width 0.1)
				(type default)
			)
			(layer "B.Fab")
		)
		(fp_line
			(start 0.299974 -0.150114)
			(end -0.299974 -0.150114)
			(stroke
				(width 0.1)
				(type default)
			)
			(layer "B.Fab")
		)
		(fp_line
			(start -0.299974 0.150114)
			(end 0.299974 0.150114)
			(stroke
				(width 0.1)
				(type default)
			)
			(layer "B.Fab")
		)
		(fp_line
			(start -0.299974 -0.150114)
			(end -0.299974 0.150114)
			(stroke
				(width 0.1)
				(type default)
			)
			(layer "B.Fab")
		)
		(pad "1" smd rect
			(at 0.2667 0)
			(size 0.3048 0.381)
			(layers "B.Cu" "B.Mask" "B.Paste")
			(net "P0V8_SERDES_VDDA_PEX0")
		)
		(pad "2" smd rect
			(at -0.2667 0)
			(size 0.3048 0.381)
			(layers "B.Cu" "B.Mask" "B.Paste")
			(net "GND")
		)
	)
	(footprint ""
		(layer "B.Cu")
		(at 135.73887 -222.214186)
		(property "Reference" "R3464"
			(at 0 0 0)
			(layer "B.SilkS")
			(hide yes)
			(effects
				(font
					(size 1.27 1.27)
				)
				(justify mirror)
			)
		)
		(property "Value" ""
			(at 0 0 0)
			(layer "B.Fab")
			(effects
				(font
					(size 1.27 1.27)
				)
				(justify mirror)
			)
		)
		(duplicate_pad_numbers_are_jumpers no)
		(fp_line
			(start -0.7874 -0.4064)
			(end -0.7874 0.4064)
			(stroke
				(width 0.1524)
				(type default)
			)
			(layer "B.SilkS")
		)
		(fp_line
			(start -0.7874 0.4064)
			(end 0.7874 0.4064)
			(stroke
				(width 0.1524)
				(type default)
			)
			(layer "B.SilkS")
		)
		(fp_line
			(start 0.7874 -0.4064)
			(end -0.7874 -0.4064)
			(stroke
				(width 0.1524)
				(type default)
			)
			(layer "B.SilkS")
		)
		(fp_line
			(start 0.7874 0.4064)
			(end 0.7874 -0.4064)
			(stroke
				(width 0.1524)
				(type default)
			)
			(layer "B.SilkS")
		)
		(fp_line
			(start -0.67945 -0.3048)
			(end -0.67945 0.3048)
			(stroke
				(width 0.1)
				(type default)
			)
			(layer "B.Fab")
		)
		(fp_line
			(start -0.67945 0.3048)
			(end -0.120396 0.3048)
			(stroke
				(width 0.1)
				(type default)
			)
			(layer "B.Fab")
		)
		(fp_line
			(start -0.12065 -0.3048)
			(end -0.67945 -0.3048)
			(stroke
				(width 0.1)
				(type default)
			)
			(layer "B.Fab")
		)
		(fp_line
			(start -0.12065 -0.2794)
			(end -0.12065 -0.3048)
			(stroke
				(width 0.1)
				(type default)
			)
			(layer "B.Fab")
		)
		(fp_line
			(start -0.120396 0.2794)
			(end 0.12065 0.2794)
			(stroke
				(width 0.1)
				(type default)
			)
			(layer "B.Fab")
		)
		(fp_line
			(start -0.120396 0.3048)
			(end -0.120396 0.2794)
			(stroke
				(width 0.1)
				(type default)
			)
			(layer "B.Fab")
		)
		(fp_line
			(start 0.12065 -0.305054)
			(end 0.12065 -0.2794)
			(stroke
				(width 0.1)
				(type default)
			)
			(layer "B.Fab")
		)
		(fp_line
			(start 0.12065 -0.2794)
			(end -0.12065 -0.2794)
			(stroke
				(width 0.1)
				(type default)
			)
			(layer "B.Fab")
		)
		(fp_line
			(start 0.12065 0.2794)
			(end 0.12065 0.3048)
			(stroke
				(width 0.1)
				(type default)
			)
			(layer "B.Fab")
		)
		(fp_line
			(start 0.12065 0.3048)
			(end 0.67945 0.3048)
			(stroke
				(width 0.1)
				(type default)
			)
			(layer "B.Fab")
		)
		(fp_line
			(start 0.67945 -0.305054)
			(end 0.12065 -0.305054)
			(stroke
				(width 0.1)
				(type default)
			)
			(layer "B.Fab")
		)
		(fp_line
			(start 0.67945 0.3048)
			(end 0.67945 -0.305054)
			(stroke
				(width 0.1)
				(type default)
			)
			(layer "B.Fab")
		)
		(pad "1" smd circle
			(at 0.40005 0 180)
			(size 0 0)
			(layers "B.Cu" "B.Mask" "B.Paste")
			(net "SPI_PEX1_SDIO0_MUX")
		)
		(pad "2" smd circle
			(at -0.40005 0 180)
			(size 0 0)
			(layers "B.Cu" "B.Mask" "B.Paste")
			(net "SPI_PEX1_SDIO0_MUX_R")
		)
	)
)
